# BASEBOARD_FAB2 (Tioga Pass) — schematic netlist excerpt (pin names and nets, part order shuffled) for the footprints in the layout excerpt that follows; sources: Cadence DE-HDL packaged netlist, KiCad conversion of Wiwynn_Tioga_Pass_MB.brd

C9N4  CAP  0.22UF 16V 10% X7R  pkg 0402  page 182 : A = P3E_CPU1_PE3_MP_C_TXP<11> ; B = P3E_CPU1_PE3_MP_TXP<11>
C9L4  CAPP  470UF 2.5V 20% ALUM  pkg 3018  page 228 : A = PVDDQ_KLM ; B = GND
R9M1  RES  1.00K 1% CHIP  pkg 0402  page 100 : A = PVDDQ_KLM ; B = M_K_VREF

(kicad_pcb
	(version 20260206)
	(generator "pcbnew")
	(generator_version "10.0")
	(general
		(thickness 1.6)
		(legacy_teardrops no)
	)
	(paper "A4")
	(title_block
		(title "Wiwynn_Tioga_Pass_MB.brd")
		(comment 1 "Tioga Pass / footprints 3340-3342 of 4770")
	)
	(layers
		(0 "F.Cu" signal "TOP")
		(4 "In1.Cu" signal "L2GND")
		(6 "In2.Cu" signal "L3")
		(8 "In3.Cu" signal "L4GND")
		(10 "In4.Cu" signal "L5")
		(12 "In5.Cu" signal "L6GND")
		(14 "In6.Cu" signal "L7VCC")
		(16 "In7.Cu" signal "L8VCC")
		(18 "In8.Cu" signal "L9GND")
		(20 "In9.Cu" signal "L10")
		(22 "In10.Cu" signal "L11GND")
		(24 "In11.Cu" signal "L12")
		(26 "In12.Cu" signal "L13GND")
		(2 "B.Cu" signal "BOTTOM")
		(9 "F.Adhes" user "F.Adhesive")
		(11 "B.Adhes" user "B.Adhesive")
		(13 "F.Paste" user "Package Geometry/Pastemask Top")
		(15 "B.Paste" user "Package Geometry/Pastemask Bottom")
		(5 "F.SilkS" user "Ref Des/Silkscreen Top")
		(7 "B.SilkS" user "Ref Des/Silkscreen Bottom")
		(1 "F.Mask" user "Board Geometry/Soldermask Top")
		(3 "B.Mask" user "Board Geometry/Soldermask Bottom")
		(17 "Dwgs.User" user "User.Drawings")
		(19 "Cmts.User" user "User.Comments")
		(21 "Eco1.User" user "User.Eco1")
		(23 "Eco2.User" user "User.Eco2")
		(25 "Edge.Cuts" user "Board Geometry/Outline")
		(27 "Margin" user)
		(31 "F.CrtYd" user "Package Geometry/Place Bound Top")
		(29 "B.CrtYd" user "Package Geometry/Place Bound Bottom")
		(35 "F.Fab" user "Ref Des/Assembly Top")
		(33 "B.Fab" user "Ref Des/Assembly Bottom")
	)
	(footprint ""
		(layer "B.Cu")
		(at 28.801568 -134.874 180)
		(property "Reference" "R9M1"
			(at 0 0 0)
			(layer "B.SilkS")
			(hide yes)
			(effects
				(font
					(size 1.27 1.27)
				)
				(justify mirror)
			)
		)
		(property "Value" ""
			(at 0 0 0)
			(layer "B.Fab")
			(effects
				(font
					(size 1.27 1.27)
				)
				(justify mirror)
			)
		)
		(duplicate_pad_numbers_are_jumpers no)
		(fp_poly
			(pts
				(xy 0.2794 -0.1016) (xy -0.2794 -0.1016) (xy -0.2794 0.9906) (xy 0.2794 0.9906)
			)
			(stroke
				(width 0)
				(type default)
			)
			(fill no)
			(layer "B.CrtYd")
		)
		(fp_line
			(start 0.2794 0.9906)
			(end -0.2794 0.9906)
			(stroke
				(width 0.1)
				(type default)
			)
			(layer "B.Fab")
		)
		(fp_line
			(start 0.2794 -0.1016)
			(end 0.2794 0.9906)
			(stroke
				(width 0.1)
				(type default)
			)
			(layer "B.Fab")
		)
		(fp_line
			(start -0.2794 0.9906)
			(end -0.2794 -0.1016)
			(stroke
				(width 0.1)
				(type default)
			)
			(layer "B.Fab")
		)
		(fp_line
			(start -0.2794 -0.1016)
			(end 0.2794 -0.1016)
			(stroke
				(width 0.1)
				(type default)
			)
			(layer "B.Fab")
		)
		(pad "1" smd rect
			(at 0 0)
			(size 0.508 0.508)
			(layers "B.Cu" "B.Mask" "B.Paste")
			(net "PVDDQ_KLM")
		)
		(pad "2" smd rect
			(at 0 0.889)
			(size 0.508 0.508)
			(layers "B.Cu" "B.Mask" "B.Paste")
			(net "M_K_VREF")
		)
		(zone
			(layer "B.Cu")
			(hatch none 0.5)
			(connect_pads
				(clearance 0)
			)
			(min_thickness 0.25)
			(keepout
				(tracks not_allowed)
				(vias allowed)
				(pads allowed)
				(copperpour not_allowed)
				(footprints allowed)
			)
			(placement
				(enabled no)
				(sheetname "")
			)
			(fill
				(thermal_gap 0.5)
				(thermal_bridge_width 0.5)
				(island_removal_mode 0)
			)
			(polygon
				(pts
					(xy 28.547568 -135.509) (xy 29.055568 -135.509) (xy 29.055568 -135.128) (xy 28.547568 -135.128)
				)
			)
		)
		(zone
			(layer "B.Cu")
			(hatch none 0.5)
			(connect_pads
				(clearance 0)
			)
			(min_thickness 0.25)
			(keepout
				(tracks allowed)
				(vias not_allowed)
				(pads allowed)
				(copperpour not_allowed)
				(footprints allowed)
			)
			(placement
				(enabled no)
				(sheetname "")
			)
			(fill
				(thermal_gap 0.5)
				(thermal_bridge_width 0.5)
				(island_removal_mode 0)
			)
			(polygon
				(pts
					(xy 28.547568 -135.128) (xy 29.055568 -135.128) (xy 29.055568 -135.509) (xy 28.547568 -135.509)
				)
			)
		)
	)
	(footprint ""
		(layer "B.Cu")
		(at 18.0594 -149.5044 -90)
		(property "Reference" "C9L4"
			(at -1.97993 9.0424 0)
			(unlocked yes)
			(layer "B.SilkS")
			(effects
				(font
					(size 0.7874 0.5842)
					(thickness 0.1524)
				)
				(justify mirror)
			)
		)
		(property "Value" ""
			(at 0 0 90)
			(layer "B.Fab")
			(effects
				(font
					(size 1.27 1.27)
				)
				(justify mirror)
			)
		)
		(duplicate_pad_numbers_are_jumpers no)
		(fp_line
			(start -2.286 7.366)
			(end -1.600708 7.366)
			(stroke
				(width 0.1524)
				(type default)
			)
			(layer "B.SilkS")
		)
		(fp_line
			(start -2.286 7.366)
			(end -2.286 1.63195)
			(stroke
				(width 0.1524)
				(type default)
			)
			(layer "B.SilkS")
		)
		(fp_line
			(start 2.286 7.366)
			(end 1.60147 7.366)
			(stroke
				(width 0.1524)
				(type default)
			)
			(layer "B.SilkS")
		)
		(fp_line
			(start 2.286 7.366)
			(end 2.286 1.632712)
			(stroke
				(width 0.1524)
				(type default)
			)
			(layer "B.SilkS")
		)
		(fp_line
			(start -2.504948 1.633728)
			(end -1.6002 1.633728)
			(stroke
				(width 0.1524)
				(type default)
			)
			(layer "B.SilkS")
		)
		(fp_line
			(start 2.563114 1.633728)
			(end 1.6002 1.633728)
			(stroke
				(width 0.1524)
				(type default)
			)
			(layer "B.SilkS")
		)
		(fp_line
			(start -2.504948 -1.616456)
			(end -2.504948 1.633728)
			(stroke
				(width 0.1524)
				(type default)
			)
			(layer "B.SilkS")
		)
		(fp_line
			(start -1.6002 -1.616456)
			(end -2.504948 -1.616456)
			(stroke
				(width 0.1524)
				(type default)
			)
			(layer "B.SilkS")
		)
		(fp_line
			(start 1.6002 -1.616456)
			(end 2.563114 -1.616456)
			(stroke
				(width 0.1524)
				(type default)
			)
			(layer "B.SilkS")
		)
		(fp_line
			(start 2.563114 -1.616456)
			(end 2.563114 1.633728)
			(stroke
				(width 0.1524)
				(type default)
			)
			(layer "B.SilkS")
		)
		(fp_rect
			(start 2.286 -0.254)
			(end -2.286 7.366)
			(stroke
				(width 0)
				(type default)
			)
			(fill no)
			(layer "B.CrtYd")
		)
		(fp_line
			(start -2.286 7.366)
			(end 2.286 7.366)
			(stroke
				(width 0.1)
				(type default)
			)
			(layer "B.Fab")
		)
		(fp_line
			(start 2.286 7.366)
			(end 2.286 -0.254)
			(stroke
				(width 0.1)
				(type default)
			)
			(layer "B.Fab")
		)
		(fp_line
			(start -2.286 -0.254)
			(end -2.286 7.366)
			(stroke
				(width 0.1)
				(type default)
			)
			(layer "B.Fab")
		)
		(fp_line
			(start 2.286 -0.254)
			(end -2.286 -0.254)
			(stroke
				(width 0.1)
				(type default)
			)
			(layer "B.Fab")
		)
		(pad "1" smd rect
			(at 0 0 90)
			(size 2.54 3.048)
			(layers "B.Cu" "B.Mask" "B.Paste")
			(net "PVDDQ_KLM")
		)
		(pad "2" smd rect
			(at 0 7.112 90)
			(size 2.54 3.048)
			(layers "B.Cu" "B.Mask" "B.Paste")
			(net "GND")
		)
	)
	(footprint ""
		(layer "B.Cu")
		(at 13.84046 -106.59618 90)
		(property "Reference" "C9N4"
			(at 0 0 90)
			(layer "B.SilkS")
			(hide yes)
			(effects
				(font
					(size 1.27 1.27)
				)
				(justify mirror)
			)
		)
		(property "Value" ""
			(at 0 0 90)
			(layer "B.Fab")
			(effects
				(font
					(size 1.27 1.27)
				)
				(justify mirror)
			)
		)
		(duplicate_pad_numbers_are_jumpers no)
		(fp_poly
			(pts
				(xy -0.3048 -0.1016) (xy -0.3048 0.9906) (xy 0.3048 0.9906) (xy 0.3048 -0.1016)
			)
			(stroke
				(width 0)
				(type default)
			)
			(fill no)
			(layer "B.CrtYd")
		)
		(fp_line
			(start 0.3048 -0.1016)
			(end 0.3048 0.9906)
			(stroke
				(width 0.1)
				(type default)
			)
			(layer "B.Fab")
		)
		(fp_line
			(start -0.3048 -0.1016)
			(end 0.3048 -0.1016)
			(stroke
				(width 0.1)
				(type default)
			)
			(layer "B.Fab")
		)
		(fp_line
			(start 0.3048 0.9906)
			(end -0.3048 0.9906)
			(stroke
				(width 0.1)
				(type default)
			)
			(layer "B.Fab")
		)
		(fp_line
			(start -0.3048 0.9906)
			(end -0.3048 -0.1016)
			(stroke
				(width 0.1)
				(type default)
			)
			(layer "B.Fab")
		)
		(pad "1" smd rect
			(at 0 0 270)
			(size 0.508 0.508)
			(layers "B.Cu" "B.Mask" "B.Paste")
			(net "P3E_CPU1_PE3_MP_C_TXP<11>")
		)
		(pad "2" smd rect
			(at 0 0.889 270)
			(size 0.508 0.508)
			(layers "B.Cu" "B.Mask" "B.Paste")
			(net "P3E_CPU1_PE3_MP_TXP<11>")
		)
		(zone
			(layer "B.Cu")
			(hatch none 0.5)
			(connect_pads
				(clearance 0)
			)
			(min_thickness 0.25)
			(keepout
				(tracks allowed)
				(vias not_allowed)
				(pads allowed)
				(copperpour not_allowed)
				(footprints allowed)
			)
			(placement
				(enabled no)
				(sheetname "")
			)
			(fill
				(thermal_gap 0.5)
				(thermal_bridge_width 0.5)
				(island_removal_mode 0)
			)
			(polygon
				(pts
					(xy 14.09446 -106.85018) (xy 14.09446 -106.34218) (xy 14.47546 -106.34218) (xy 14.47546 -106.85018)
				)
			)
		)
		(zone
			(layer "B.Cu")
			(hatch none 0.5)
			(connect_pads
				(clearance 0)
			)
			(min_thickness 0.25)
			(keepout
				(tracks not_allowed)
				(vias allowed)
				(pads allowed)
				(copperpour not_allowed)
				(footprints allowed)
			)
			(placement
				(enabled no)
				(sheetname "")
			)
			(fill
				(thermal_gap 0.5)
				(thermal_bridge_width 0.5)
				(island_removal_mode 0)
			)
			(polygon
				(pts
					(xy 14.47546 -106.85018) (xy 14.47546 -106.34218) (xy 14.09446 -106.34218) (xy 14.09446 -106.85018)
				)
			)
		)
	)
)
